# T6G (Grand Teton) — schematic parts with pin connectivity, parts 5636–5788 of 8303; source: Cadence DE-HDL packaged netlist (pstxprt.dat, pstxnet.dat, pstchip.dat)

R912  Q_RES  4.7K 5% EMPTY  pkg 0201LF  page 353 : 1 = P1V8_CPU1_RT_1D ; 2 = JTAG_TEST_MODE_RT_CPU1_P3
R913  Q_RES  0 5% CHIP  pkg 0201LF  page 353 : 1 = SMB_RT_CPU1_P3_R_SCL ; 2 = SMB_RT_CPU1_P3_R2_SCL
R914  Q_RES  0 5% CHIP  pkg 0201LF  page 353 : 1 = SMB_RT_CPU1_P3_R_SDA ; 2 = SMB_RT_CPU1_P3_R2_SDA
R915  Q_RES  4.7K 5% EMPTY  pkg 0201LF  page 353 : 1 = P1V8_CPU1_RT_1D ; 2 = GPIO2_RT_CPU1_P3
R916  Q_RES  10K 1% CHIP  pkg 0201LF  page 353 : 1 = GPIO2_RT_CPU1_P3 ; 2 = GND
R917  Q_RES  10K 1% CHIP  pkg 0201LF  page 353 : 1 = GPIO3_RT_CPU1_P3 ; 2 = GND
R918  Q_RES  4.7K 5% EMPTY  pkg 0201LF  page 353 : 1 = P1V8_CPU1_RT_1D ; 2 = TEST0_RT_CPU1_P3
R919  Q_RES  4.7K 5% CHIP  pkg 0201LF  page 353 : 1 = TEST0_RT_CPU1_P3 ; 2 = GND
R920  Q_RES  4.7K 5% EMPTY  pkg 0201LF  page 353 : 1 = P1V8_CPU1_RT_1D ; 2 = TEST1_RT_CPU1_P3
R921  Q_RES  4.7K 5% CHIP  pkg 0201LF  page 353 : 1 = TEST1_RT_CPU1_P3 ; 2 = GND
R922  Q_RES  4.7K 5% EMPTY  pkg 0201LF  page 353 : 1 = P1V8_CPU1_RT_1D ; 2 = TEST2_RT_CPU1_P3
R923  Q_RES  4.7K 5% CHIP  pkg 0201LF  page 353 : 1 = TEST2_RT_CPU1_P3 ; 2 = GND
R924  Q_RES  4.7K 5% CHIP  pkg 0201LF  page 353 : 1 = JTAG_TEST_MODE_RT_CPU1_P3 ; 2 = GND
R925  Q_RES  4.7K 5% CHIP  pkg 0201LF  page 353 : 1 = P1V8_CPU1_RT_1D ; 2 = MODE_RT_CPU1_P3
R926  Q_RES  4.7K 5% EMPTY  pkg 0201LF  page 353 : 1 = MODE_RT_CPU1_P3 ; 2 = GND
R927  Q_RES  1K 1% EMPTY  pkg 0201LF  page 353 : 1 = P1V8_CPU1_RT_1D ; 2 = RT_CPU1_P3_ADDR1
R928  Q_RES  0 5% CHIP  pkg 0402LF  page 54 : 1 = CPU1_XTRIG_R2_L7 ; 2 = CPU1_XTRIG_L7
R929  Q_RES  0 5% CHIP  pkg 0402LF  page 54 : 1 = CPU1_XTRIG_L4 ; 2 = CPU1_XTRIG_R1_L4
R930  Q_RES  0 5% CHIP  pkg 0402LF  page 54 : 1 = CPU1_XTRIG_L5 ; 2 = CPU1_XTRIG_R1_L5
R931  Q_RES  0 5% CHIP  pkg 0402LF  page 54 : 1 = CPU1_XTRIG_L6 ; 2 = CPU1_XTRIG_R1_L6
R932  Q_RES  0 5% CHIP  pkg 0402LF  page 54 : 1 = CPU1_XTRIG_L7 ; 2 = CPU1_XTRIG_R1_L7
R933  Q_RES  33 5% CHIP  pkg 0402LF  page 81 : 1 = FM_SMERR_LED_R_N ; 2 = FM_SMERR_LED_N
R934  Q_RES  0 5% CHIP  pkg 0402LF  page 166 : 1 = FM_BIOS_POST_CMPLT_N ; 2 = BOOT_RDY_R1_N
R935  Q_RES  0 5% CHIP  pkg 0402LF  page 166 : 1 = BOOT_RDY_BUF_R_LED ; 2 = BOOT_RDY_BUF_LED
R936  Q_RES  0 5% CHIP  pkg 0402LF  page 166 : 1 = FM_SMERR_BUF_LED_N ; 2 = FM_SMERR_BUF_R_LED_N
R937  Q_RES  0 5% CHIP  pkg 0402LF  page 81 : 1 = FM_BIOS_POST_CMPLT_BUF_R_N ; 2 = FM_BIOS_POST_CMPLT_BUF_N
R938  Q_RES  4.7K 5% CHIP  pkg 0402LF  page 28 : 1 = BOOT_RDY_H ; 2 = PVDD18_S5_P0
R939  Q_RES  0 5% CHIP  pkg 0402LF  page 28 : 1 = FM_BIOS_POST_CMPLT_R_N ; 2 = FM_BIOS_POST_CMPLT_N
R940  Q_RES  0 5% CHIP  pkg 0402LF  page 28 : 1 = BOOT_RDY_R_H ; 2 = BOOT_RDY_H
R941  Q_RES  0 5% EMPTY  pkg 0402LF  page 166 : 1 = BOOT_RDY_H ; 2 = BOOT_RDY_R1_N
R942  Q_RES  4.7K 5% CHIP  pkg 0402LF  page 34 : 1 = PVDD18_S5_P0 ; 2 = FM_BIOS_POST_CMPLT_N
R943  Q_RES  4.7K 5% CHIP  pkg 0402LF  page 34 : 1 = P1V8_AUX ; 2 = FM_BIOS_POST_CMPLT_BUF_R1_N
R944  Q_RES  4.7K 5% CHIP  pkg 0402LF  page 166 : 1 = P3V3_AUX ; 2 = BOOT_RDY_BUF_LED
R945  Q_RES  4.7K 5% CHIP  pkg 0402LF  page 166 : 1 = P3V3_AUX ; 2 = FM_SMERR_BUF_R_LED_N
R946  Q_RES  4.7K 5% CHIP  pkg 0402LF  page 166 : 1 = P3V3_AUX ; 2 = BOOT_RDY_LED
R947  Q_RES  4.7K 5% CHIP  pkg 0402LF  page 166 : 1 = P3V3_AUX ; 2 = SMERR_LED
R948  Q_RES  130 1% CHIP  pkg 0402LF  page 166 : 1 = PU_BOOT_RDY_LED ; 2 = P3V3_AUX
R949  Q_RES  1K 1% CHIP  pkg 0201LF  page 353 : 1 = RT_CPU1_P3_ADDR1 ; 2 = GND
R950  Q_RES  249 1% CHIP  pkg 0402LF  page 166 : 1 = PU_SMERR_LED ; 2 = P3V3_AUX
R951  Q_RES  0 5% EMPTY  pkg 0402LF  page 279 : 1 = P1V8_CPU0_RT0_1A_1D ; 2 = P1V8_CPU0_RT0_1A
R952  Q_RES  0 5% EMPTY  pkg 0402LF  page 279 : 1 = P1V8_CPU0_RT0_1A_1D ; 2 = P1V8_CPU0_RT0_1A
R953  Q_RES  0 5% CHIP  pkg 0201LF  page 276 : 1 = RST_RT_CPU0_P0_PERST_N ; 2 = RST_RT_CPU0_P0_PERST_R_N
R954  Q_RES  11.5K 1% EMPTY  pkg 0402LF  page 169 : 1 = P3V3_AUX_DSC_VOL ; 2 = GND
R955  Q_RES  0 5% CHIP  pkg 0402LF  page 145 : 1 = FM_LED_ACTIVE_E1S_0 ; 2 = FM_LED_ACTIVE_E1S_0_R
R956  Q_RES  0 5% CHIP  pkg 0402LF  page 133 : 1 = RST_PERST_OCP_SFF_BUF2_N ; 2 = RST_PERST3_OCP_SFF_N
R957  Q_RES  33 5% CHIP  pkg 0402LF  page 81 : 1 = FM_RST_PERST_SCM_R_N ; 2 = FM_RST_PERST_SCM_N
R958  Q_RES  33 5% CHIP  pkg 0402LF  page 82 : 1 = FM_PLD_OCP_SFF_AUX_PWR_EN ; 2 = FM_PLD_OCP_SFF_AUX_PWR_R_EN
R959  Q_RES  33 5% CHIP  pkg 0402LF  page 82 : 1 = OCP_SFF_MAIN_PWR_EN ; 2 = FM_PLD_OCP_SFF_MAIN_PWR_EN_R
R960  Q_RES  0 5% EMPTY  pkg 0402LF  page 279 : 1 = P1V8_CPU0_RT_1D ; 2 = P1V8_CPU0_RT0_1A_1D
R961  Q_RES  0 5% EMPTY  pkg 0603LF  page 279 : 1 = P0V9_CPU0_RT_2D ; 2 = P0V9_CPU0_RT0_2A_2D
R962  Q_RES  0 5% CHIP  pkg 0603LF  page 279 : 1 = P0V9_CPU0_RT0_2A_2D ; 2 = P0V9_CPU0_RT0_2A
R963  Q_RES  0 5% CHIP  pkg 0201LF  page 276 : 1 = RST_RT_CPU0_P0_RESET_N ; 2 = RST_RT_CPU0_P0_RESET_R_N
R964  Q_RES  1K 1% CHIP  pkg 0201LF  page 276 : 1 = P1V8_CPU0_RT_1D ; 2 = RT_CPU0_P0_ADDR3
R965  Q_RES  1K 1% EMPTY  pkg 0201LF  page 276 : 1 = RT_CPU0_P0_ADDR3 ; 2 = GND
R966  Q_RES  1K 1% EMPTY  pkg 0201LF  page 276 : 1 = P1V8_CPU0_RT_1D ; 2 = RT_CPU0_P0_ADDR2
R967  Q_RES  20K 1% CHIP  pkg 0201LF  page 276 : 1 = RT_CPU0_P0_ADDR2 ; 2 = GND
R968  Q_RES  1K 1% EMPTY  pkg 0201LF  page 276 : 1 = P1V8_CPU0_RT_1D ; 2 = RT_CPU0_P0_ADDR1
R969  Q_RES  1K 1% CHIP  pkg 0201LF  page 276 : 1 = RT_CPU0_P0_ADDR1 ; 2 = GND
R970  Q_RES  10K 1% CHIP  pkg 0201LF  page 276 : 1 = RST_RT_CPU0_P0_PERST_R_N ; 2 = GND
R971  Q_RES  10K 1% CHIP  pkg 0201LF  page 276 : 1 = RST_RT_CPU0_P0_RESET_R_N ; 2 = GND
R972  Q_RES  4.7K 5% EMPTY  pkg 0201LF  page 276 : 1 = P1V8_CPU0_RT_1D ; 2 = RT_CPU0_P0_SCAN_MODE
R973  Q_RES  200 1% CHIP  pkg 0201LF  page 276 : 1 = RT_CPU0_P0_SCAN_MODE ; 2 = GND
R974  Q_RES  4.7K 5% EMPTY  pkg 0201LF  page 276 : 1 = P1V8_CPU0_RT_1D ; 2 = RST_RT_CPU0_P0_RESET_R_N
R975  Q_RES  4.7K 5% EMPTY  pkg 0201LF  page 276 : 1 = P1V8_CPU0_RT_1D ; 2 = JTAG_TEST_MODE_RT_CPU0_P0
R976  Q_RES  0 5% CHIP  pkg 0201LF  page 276 : 1 = SMB_RT_CPU0_P0_R_SCL ; 2 = SMB_RT_CPU0_P0_R2_SCL
R977  Q_RES  0 5% CHIP  pkg 0201LF  page 276 : 1 = SMB_RT_CPU0_P0_R_SDA ; 2 = SMB_RT_CPU0_P0_R2_SDA
R978  Q_RES  4.7K 5% EMPTY  pkg 0201LF  page 276 : 1 = P1V8_CPU0_RT_1D ; 2 = GPIO2_RT_CPU0_P0
R979  Q_RES  10K 1% CHIP  pkg 0201LF  page 276 : 1 = GPIO2_RT_CPU0_P0 ; 2 = GND
R980  Q_RES  10K 1% CHIP  pkg 0201LF  page 276 : 1 = GPIO3_RT_CPU0_P0 ; 2 = GND
R981  Q_RES  4.7K 5% EMPTY  pkg 0201LF  page 276 : 1 = P1V8_CPU0_RT_1D ; 2 = TEST0_RT_CPU0_P0
R982  Q_RES  4.7K 5% CHIP  pkg 0201LF  page 276 : 1 = TEST0_RT_CPU0_P0 ; 2 = GND
R983  Q_RES  4.7K 5% EMPTY  pkg 0201LF  page 276 : 1 = P1V8_CPU0_RT_1D ; 2 = TEST1_RT_CPU0_P0
R984  Q_RES  4.7K 5% CHIP  pkg 0201LF  page 276 : 1 = TEST1_RT_CPU0_P0 ; 2 = GND
R985  Q_RES  4.7K 5% EMPTY  pkg 0201LF  page 276 : 1 = P1V8_CPU0_RT_1D ; 2 = TEST2_RT_CPU0_P0
R986  Q_RES  0 5% EMPTY  pkg 0402LF  page 159 : 1 = I3C_1_SPD_DDRGL_CPU0_R_SCL ; 2 = I3C_SPD_DDRGL_CPU0_BYPASS_SCL
R987  Q_RES  0 5% EMPTY  pkg 0402LF  page 159 : 1 = I3C_1_SPD_DDRGL_CPU0_R_SDA ; 2 = I3C_SPD_DDRGL_CPU0_BYPASS_SDA
R988  Q_RES  0 5% EMPTY  pkg 0402LF  page 159 : 1 = I3C_0_SPD_DDRAF_CPU1_R_SCL ; 2 = I3C_SPD_DDRAF_CPU1_BYPASS_SCL
R989  Q_RES  0 5% EMPTY  pkg 0402LF  page 159 : 1 = I3C_0_SPD_DDRAF_CPU1_R_SDA ; 2 = I3C_SPD_DDRAF_CPU1_BYPASS_SDA
R990  Q_RES  0 5% EMPTY  pkg 0402LF  page 159 : 1 = I3C_1_SPD_DDRGL_CPU1_R_SCL ; 2 = I3C_SPD_DDRGL_CPU1_BYPASS_SCL
R991  Q_RES  0 5% EMPTY  pkg 0402LF  page 159 : 1 = I3C_1_SPD_DDRGL_CPU1_R_SDA ; 2 = I3C_SPD_DDRGL_CPU1_BYPASS_SDA
R992  Q_RES  33 5% CHIP  pkg 0402LF  page 80 : 1 = FM_SYS_THROTTLE_R_N ; 2 = FM_SYS_THROTTLE_N
R993  Q_RES  1K 1% CHIP  pkg 0402LF  page 83 : 1 = FM_SYS_THROTTLE_N ; 2 = P3V3_AUX
R994  Q_RES  10K 1% CHIP  pkg 0402LF  page 155 : 1 = P3V3_AUX ; 2 = IRQ_LVC3_WAKE_N
R995  Q_RES  4.7K 5% CHIP  pkg 0201LF  page 276 : 1 = TEST2_RT_CPU0_P0 ; 2 = GND
R996  Q_RES  4.7K 5% CHIP  pkg 0402LF  page 84 : 1 = P1V8_AUX ; 2 = SCM_IRQ_1V8_N
R997  Q_RES  4.7K 5% CHIP  pkg 0201LF  page 276 : 1 = JTAG_TEST_MODE_RT_CPU0_P0 ; 2 = GND
R998  Q_RES  4.7K 5% CHIP  pkg 0201LF  page 276 : 1 = P1V8_CPU0_RT_1D ; 2 = MODE_RT_CPU0_P0
R999  Q_RES  4.7K 5% CHIP  pkg 0402LF  page 145 : 1 = FM_LED_ACTIVE_E1S_0_R ; 2 = GND
R1000  Q_RES  4.7K 5% CHIP  pkg 0402LF  page 145 : 1 = FM_LED_ACTIVE_E1S_0_BUF ; 2 = GND
R1001  Q_RES  4.7K 5% EMPTY  pkg 0201LF  page 276 : 1 = MODE_RT_CPU0_P0 ; 2 = GND
R1002  Q_RES  0 5% EMPTY  pkg 0402LF  page 290 : 1 = P1V8_CPU0_RT1_1A_1D ; 2 = P1V8_CPU0_RT1_1A
R1003  Q_RES  0 5% EMPTY  pkg 0402LF  page 290 : 1 = P1V8_CPU0_RT1_1A_1D ; 2 = P1V8_CPU0_RT1_1A
R1004  Q_RES  0 5% CHIP  pkg 0201LF  page 287 : 1 = RST_RT_CPU0_P1_PERST_N ; 2 = RST_RT_CPU0_P1_PERST_R_N
R1005  Q_RES  33 5% CHIP  pkg 0402LF  page 155 : 1 = M2_0_PEWAKE_R_N ; 2 = IRQ_LVC3_WAKE_N
R1006  Q_RES  4.7K 5% EMPTY  pkg 0201LF  page 287 : 1 = MODE_RT_CPU0_P1 ; 2 = GND
R1007  Q_RES  2K 1% EMPTY  pkg 0402LF  page 169 : 1 = P12V_AUX ; 2 = P12V_AUX_DSC_G1
R1008  Q_RES  0 5% EMPTY  pkg 0402LF  page 290 : 1 = P1V8_CPU0_RT_1D ; 2 = P1V8_CPU0_RT1_1A_1D
R1009  Q_RES  10K 1% CHIP  pkg 0402LF  page 155 : 1 = P3V3_AUX ; 2 = IRQ_LVC3_WAKE
R1010  Q_RES  0 5% EMPTY  pkg 0603LF  page 290 : 1 = P0V9_CPU0_RT_2D ; 2 = P0V9_CPU0_RT1_2A_2D
R1011  Q_RES  0 5% CHIP  pkg 0603LF  page 290 : 1 = P0V9_CPU0_RT1_2A_2D ; 2 = P0V9_CPU0_RT1_2A
R1012  Q_RES  0 5% CHIP  pkg 0201LF  page 287 : 1 = RST_RT_CPU0_P1_RESET_N ; 2 = RST_RT_CPU0_P1_RESET_R_N
R1013  Q_RES  1K 1% CHIP  pkg 0201LF  page 287 : 1 = P1V8_CPU0_RT_1D ; 2 = RT_CPU0_P1_ADDR3
R1014  Q_RES  1K 1% EMPTY  pkg 0201LF  page 287 : 1 = RT_CPU0_P1_ADDR3 ; 2 = GND
R1015  Q_RES  1K 1% EMPTY  pkg 0201LF  page 287 : 1 = P1V8_CPU0_RT_1D ; 2 = RT_CPU0_P1_ADDR2
R1016  Q_RES  20K 1% CHIP  pkg 0201LF  page 287 : 1 = RT_CPU0_P1_ADDR2 ; 2 = GND
R1017  Q_RES  1K 1% EMPTY  pkg 0201LF  page 287 : 1 = P1V8_CPU0_RT_1D ; 2 = RT_CPU0_P1_ADDR1
R1018  Q_RES  1K 1% CHIP  pkg 0201LF  page 287 : 1 = RT_CPU0_P1_ADDR1 ; 2 = GND
R1019  Q_RES  10K 1% CHIP  pkg 0201LF  page 287 : 1 = RST_RT_CPU0_P1_PERST_R_N ; 2 = GND
R1020  Q_RES  10K 1% CHIP  pkg 0201LF  page 287 : 1 = RST_RT_CPU0_P1_RESET_R_N ; 2 = GND
R1021  Q_RES  4.7K 5% EMPTY  pkg 0201LF  page 287 : 1 = P1V8_CPU0_RT_1D ; 2 = RT_CPU0_P1_SCAN_MODE
R1022  Q_RES  200 1% CHIP  pkg 0201LF  page 287 : 1 = RT_CPU0_P1_SCAN_MODE ; 2 = GND
R1023  Q_RES  4.7K 5% EMPTY  pkg 0201LF  page 287 : 1 = P1V8_CPU0_RT_1D ; 2 = RST_RT_CPU0_P1_RESET_R_N
R1024  Q_RES  4.7K 5% EMPTY  pkg 0201LF  page 287 : 1 = P1V8_CPU0_RT_1D ; 2 = JTAG_TEST_MODE_RT_CPU0_P1
R1025  Q_RES  0 5% CHIP  pkg 0201LF  page 287 : 1 = SMB_RT_CPU0_P1_R_SCL ; 2 = SMB_RT_CPU0_P1_R2_SCL
R1026  Q_RES  0 5% CHIP  pkg 0201LF  page 287 : 1 = SMB_RT_CPU0_P1_R_SDA ; 2 = SMB_RT_CPU0_P1_R2_SDA
R1027  Q_RES  4.7K 5% EMPTY  pkg 0201LF  page 287 : 1 = P1V8_CPU0_RT_1D ; 2 = GPIO2_RT_CPU0_P1
R1028  Q_RES  10K 1% CHIP  pkg 0201LF  page 287 : 1 = GPIO2_RT_CPU0_P1 ; 2 = GND
R1029  Q_RES  10K 1% CHIP  pkg 0201LF  page 287 : 1 = GPIO3_RT_CPU0_P1 ; 2 = GND
R1030  Q_RES  4.7K 5% EMPTY  pkg 0201LF  page 287 : 1 = P1V8_CPU0_RT_1D ; 2 = TEST0_RT_CPU0_P1
R1031  Q_RES  4.7K 5% CHIP  pkg 0201LF  page 287 : 1 = TEST0_RT_CPU0_P1 ; 2 = GND
R1032  Q_RES  4.7K 5% EMPTY  pkg 0201LF  page 287 : 1 = P1V8_CPU0_RT_1D ; 2 = TEST1_RT_CPU0_P1
R1033  Q_RES  4.7K 5% CHIP  pkg 0201LF  page 287 : 1 = TEST1_RT_CPU0_P1 ; 2 = GND
R1034  Q_RES  4.7K 5% EMPTY  pkg 0201LF  page 287 : 1 = P1V8_CPU0_RT_1D ; 2 = TEST2_RT_CPU0_P1
R1035  Q_RES  4.7K 5% CHIP  pkg 0201LF  page 287 : 1 = TEST2_RT_CPU0_P1 ; 2 = GND
R1036  Q_RES  0 5% CHIP  pkg 0402LF  page 85 : 1 = FM_SMB_RST_E1S_0_N ; 2 = FM_SMB_RST_E1S_0_R_N
R1037  Q_RES  4.7K 5% CHIP  pkg 0201LF  page 287 : 1 = JTAG_TEST_MODE_RT_CPU0_P1 ; 2 = GND
R1038  Q_RES  0 5% CHIP  pkg 0402LF  page 145 : 1 = FM_LED_ACTIVE_E1S_0_R_BUF ; 2 = FM_LED_ACTIVE_E1S_0_BUF
R1039  Q_RES  4.7K 5% CHIP  pkg 0201LF  page 287 : 1 = P1V8_CPU0_RT_1D ; 2 = MODE_RT_CPU0_P1
R1040  Q_RES  1K 1% EMPTY  pkg 0201LF  page 288 : 1 = P1V8_CPU0_RT_1D ; 2 = RT_CPU0_P1_VQPS
R1041  Q_RES  200 1% CHIP  pkg 0201LF  page 288 : 1 = RT_CPU0_P1_VQPS ; 2 = GND
R1042  Q_RES  0 5% CHIP  pkg 0201LF  page 288 : 1 = NCF_CPU0_P1_GND ; 2 = GND
R1043  Q_RES  0 5% CHIP  pkg 0201LF  page 288 : 1 = NCF_A1_CPU0_P1_GND ; 2 = GND
R1044  Q_RES  1K 1% CHIP  pkg 0201LF  page 289 : 1 = U15_E2 ; 2 = GND
R1045  Q_RES  0 5% EMPTY  pkg 0402LF  page 301 : 1 = P1V8_CPU0_RT2_1A_1D ; 2 = P1V8_CPU0_RT2_1A
R1046  Q_RES  0 5% EMPTY  pkg 0402LF  page 301 : 1 = P1V8_CPU0_RT2_1A_1D ; 2 = P1V8_CPU0_RT2_1A
R1047  Q_RES  0 5% CHIP  pkg 0201LF  page 298 : 1 = RST_RT_CPU0_P2_PERST_N ; 2 = RST_RT_CPU0_P2_PERST_R_N
R1048  Q_RES  4.7K 5% EMPTY  pkg 0201LF  page 298 : 1 = MODE_RT_CPU0_P2 ; 2 = GND
R1049  Q_RES  1K 1% EMPTY  pkg 0402LF  page 169 : 1 = P12V_AUX_DSC_G1 ; 2 = GND
R1050  Q_RES  0 5% EMPTY  pkg 0402LF  page 301 : 1 = P1V8_CPU0_RT_1D ; 2 = P1V8_CPU0_RT2_1A_1D
R1051  Q_RES  0 5% EMPTY  pkg 0603LF  page 301 : 1 = P0V9_CPU0_RT_2D ; 2 = P0V9_CPU0_RT2_2A_2D
R1052  Q_RES  1K 1% EMPTY  pkg 0402LF  page 169 : 1 = P3V3_AUX ; 2 = P3V3_AUX_DSC_G1
R1053  Q_RES  0 5% CHIP  pkg 0603LF  page 301 : 1 = P0V9_CPU0_RT2_2A_2D ; 2 = P0V9_CPU0_RT2_2A
R1054  Q_RES  0 5% CHIP  pkg 0201LF  page 298 : 1 = RST_RT_CPU0_P2_RESET_N ; 2 = RST_RT_CPU0_P2_RESET_R_N
R1055  Q_RES  1K 1% CHIP  pkg 0201LF  page 298 : 1 = P1V8_CPU0_RT_1D ; 2 = RT_CPU0_P2_ADDR3
R1056  Q_RES  1K 1% EMPTY  pkg 0201LF  page 298 : 1 = RT_CPU0_P2_ADDR3 ; 2 = GND
R1057  Q_RES  1K 1% EMPTY  pkg 0201LF  page 298 : 1 = P1V8_CPU0_RT_1D ; 2 = RT_CPU0_P2_ADDR2
R1058  Q_RES  20K 1% CHIP  pkg 0201LF  page 298 : 1 = RT_CPU0_P2_ADDR2 ; 2 = GND
R1059  Q_RES  1K 1% EMPTY  pkg 0201LF  page 298 : 1 = P1V8_CPU0_RT_1D ; 2 = RT_CPU0_P2_ADDR1
R1060  Q_RES  1K 1% CHIP  pkg 0201LF  page 298 : 1 = RT_CPU0_P2_ADDR1 ; 2 = GND
R1061  Q_RES  10K 1% CHIP  pkg 0201LF  page 298 : 1 = RST_RT_CPU0_P2_PERST_R_N ; 2 = GND
R1062  Q_RES  10K 1% CHIP  pkg 0201LF  page 298 : 1 = RST_RT_CPU0_P2_RESET_R_N ; 2 = GND
R1063  Q_RES  4.7K 5% EMPTY  pkg 0201LF  page 298 : 1 = P1V8_CPU0_RT_1D ; 2 = RT_CPU0_P2_SCAN_MODE
R1064  Q_RES  200 1% CHIP  pkg 0201LF  page 298 : 1 = RT_CPU0_P2_SCAN_MODE ; 2 = GND
